# SCM (Grand Teton) — schematic netlist excerpt (pin names and nets, part order shuffled) for the footprints in the layout excerpt that follows; sources: Cadence DE-HDL packaged netlist, KiCad conversion of 12092022_DA0F0TMDCD0_F0T_Management_Board_D_brd_V3_OCP.brd

R789  Q_RES  2.87K 1% CHIP  pkg 0402LF  page 15 : A = P3V3_AUX ; B = P3V3_SENSOR
R814  Q_RES  10K 1% CHIP  pkg 0402LF  page 49 : A = P5V_AUX ; B = PWR_LED_BUF_N_R

(kicad_pcb
	(version 20260206)
	(generator "pcbnew")
	(generator_version "10.0")
	(general
		(thickness 1.6)
		(legacy_teardrops no)
	)
	(paper "A4")
	(title_block
		(title "12092022_DA0F0TMDCD0_F0T_Management_Board_D_brd_V3_OCP.brd")
		(comment 1 "Grand Teton / footprints 1199-1200 of 1440")
	)
	(layers
		(0 "F.Cu" signal "TOP")
		(4 "In1.Cu" signal "GND")
		(6 "In2.Cu" signal "IN1")
		(8 "In3.Cu" signal "GND1")
		(10 "In4.Cu" signal "IN2")
		(12 "In5.Cu" signal "VCC")
		(14 "In6.Cu" signal "VCC1")
		(16 "In7.Cu" signal "IN3")
		(18 "In8.Cu" signal "GND2")
		(20 "In9.Cu" signal "IN4")
		(22 "In10.Cu" signal "GND3")
		(2 "B.Cu" signal "BOTTOM")
		(9 "F.Adhes" user "F.Adhesive")
		(11 "B.Adhes" user "B.Adhesive")
		(13 "F.Paste" user "Package Geometry/Pastemask Top")
		(15 "B.Paste" user "Package Geometry/Pastemask Bottom")
		(5 "F.SilkS" user "Ref Des/Silkscreen Top")
		(7 "B.SilkS" user "Ref Des/Silkscreen Bottom")
		(1 "F.Mask" user "Board Geometry/Soldermask Top")
		(3 "B.Mask" user "Board Geometry/Soldermask Bottom")
		(17 "Dwgs.User" user "User.Drawings")
		(19 "Cmts.User" user "User.Comments")
		(21 "Eco1.User" user "User.Eco1")
		(23 "Eco2.User" user "User.Eco2")
		(25 "Edge.Cuts" user "Board Geometry/Outline")
		(27 "Margin" user)
		(31 "F.CrtYd" user "Package Geometry/Place Bound Top")
		(29 "B.CrtYd" user "Package Geometry/Place Bound Bottom")
		(35 "F.Fab" user "Ref Des/Assembly Top")
		(33 "B.Fab" user "Ref Des/Assembly Bottom")
	)
	(footprint ""
		(layer "B.Cu")
		(at 50.23866 -69.397372 90)
		(property "Reference" "R789"
			(at 0 0 90)
			(layer "B.SilkS")
			(hide yes)
			(effects
				(font
					(size 1.27 1.27)
				)
				(justify mirror)
			)
		)
		(property "Value" ""
			(at 0 0 90)
			(layer "B.Fab")
			(effects
				(font
					(size 1.27 1.27)
				)
				(justify mirror)
			)
		)
		(duplicate_pad_numbers_are_jumpers no)
		(fp_line
			(start 0.7874 -0.4064)
			(end -0.7874 -0.4064)
			(stroke
				(width 0.1524)
				(type default)
			)
			(layer "B.SilkS")
		)
		(fp_line
			(start -0.7874 -0.4064)
			(end -0.7874 0.4064)
			(stroke
				(width 0.1524)
				(type default)
			)
			(layer "B.SilkS")
		)
		(fp_line
			(start 0.7874 0.4064)
			(end 0.7874 -0.4064)
			(stroke
				(width 0.1524)
				(type default)
			)
			(layer "B.SilkS")
		)
		(fp_line
			(start -0.7874 0.4064)
			(end 0.7874 0.4064)
			(stroke
				(width 0.1524)
				(type default)
			)
			(layer "B.SilkS")
		)
		(fp_line
			(start 0.67945 -0.305054)
			(end 0.12065 -0.305054)
			(stroke
				(width 0.1)
				(type default)
			)
			(layer "B.Fab")
		)
		(fp_line
			(start 0.12065 -0.305054)
			(end 0.12065 -0.2794)
			(stroke
				(width 0.1)
				(type default)
			)
			(layer "B.Fab")
		)
		(fp_line
			(start -0.12065 -0.3048)
			(end -0.67945 -0.3048)
			(stroke
				(width 0.1)
				(type default)
			)
			(layer "B.Fab")
		)
		(fp_line
			(start -0.67945 -0.3048)
			(end -0.67945 0.3048)
			(stroke
				(width 0.1)
				(type default)
			)
			(layer "B.Fab")
		)
		(fp_line
			(start 0.12065 -0.2794)
			(end -0.12065 -0.2794)
			(stroke
				(width 0.1)
				(type default)
			)
			(layer "B.Fab")
		)
		(fp_line
			(start -0.12065 -0.2794)
			(end -0.12065 -0.3048)
			(stroke
				(width 0.1)
				(type default)
			)
			(layer "B.Fab")
		)
		(fp_line
			(start 0.12065 0.2794)
			(end 0.12065 0.3048)
			(stroke
				(width 0.1)
				(type default)
			)
			(layer "B.Fab")
		)
		(fp_line
			(start -0.120396 0.2794)
			(end 0.12065 0.2794)
			(stroke
				(width 0.1)
				(type default)
			)
			(layer "B.Fab")
		)
		(fp_line
			(start 0.67945 0.3048)
			(end 0.67945 -0.305054)
			(stroke
				(width 0.1)
				(type default)
			)
			(layer "B.Fab")
		)
		(fp_line
			(start 0.12065 0.3048)
			(end 0.67945 0.3048)
			(stroke
				(width 0.1)
				(type default)
			)
			(layer "B.Fab")
		)
		(fp_line
			(start -0.120396 0.3048)
			(end -0.120396 0.2794)
			(stroke
				(width 0.1)
				(type default)
			)
			(layer "B.Fab")
		)
		(fp_line
			(start -0.67945 0.3048)
			(end -0.120396 0.3048)
			(stroke
				(width 0.1)
				(type default)
			)
			(layer "B.Fab")
		)
		(pad "1" smd circle
			(at 0.40005 0 270)
			(size 0 0)
			(layers "B.Cu" "B.Mask" "B.Paste")
			(net "P3V3_AUX")
		)
		(pad "2" smd circle
			(at -0.40005 0 270)
			(size 0 0)
			(layers "B.Cu" "B.Mask" "B.Paste")
			(net "P3V3_SENSOR")
		)
	)
	(footprint ""
		(layer "B.Cu")
		(at 14.097 -20.447 -90)
		(property "Reference" "R814"
			(at 0 0 90)
			(layer "B.SilkS")
			(hide yes)
			(effects
				(font
					(size 1.27 1.27)
				)
				(justify mirror)
			)
		)
		(property "Value" ""
			(at 0 0 90)
			(layer "B.Fab")
			(effects
				(font
					(size 1.27 1.27)
				)
				(justify mirror)
			)
		)
		(duplicate_pad_numbers_are_jumpers no)
		(fp_line
			(start -0.7874 0.4064)
			(end 0.7874 0.4064)
			(stroke
				(width 0.1524)
				(type default)
			)
			(layer "B.SilkS")
		)
		(fp_line
			(start 0.7874 0.4064)
			(end 0.7874 -0.4064)
			(stroke
				(width 0.1524)
				(type default)
			)
			(layer "B.SilkS")
		)
		(fp_line
			(start -0.7874 -0.4064)
			(end -0.7874 0.4064)
			(stroke
				(width 0.1524)
				(type default)
			)
			(layer "B.SilkS")
		)
		(fp_line
			(start 0.7874 -0.4064)
			(end -0.7874 -0.4064)
			(stroke
				(width 0.1524)
				(type default)
			)
			(layer "B.SilkS")
		)
		(fp_line
			(start -0.67945 0.3048)
			(end -0.120396 0.3048)
			(stroke
				(width 0.1)
				(type default)
			)
			(layer "B.Fab")
		)
		(fp_line
			(start -0.120396 0.3048)
			(end -0.120396 0.2794)
			(stroke
				(width 0.1)
				(type default)
			)
			(layer "B.Fab")
		)
		(fp_line
			(start 0.12065 0.3048)
			(end 0.67945 0.3048)
			(stroke
				(width 0.1)
				(type default)
			)
			(layer "B.Fab")
		)
		(fp_line
			(start 0.67945 0.3048)
			(end 0.67945 -0.305054)
			(stroke
				(width 0.1)
				(type default)
			)
			(layer "B.Fab")
		)
		(fp_line
			(start -0.120396 0.2794)
			(end 0.12065 0.2794)
			(stroke
				(width 0.1)
				(type default)
			)
			(layer "B.Fab")
		)
		(fp_line
			(start 0.12065 0.2794)
			(end 0.12065 0.3048)
			(stroke
				(width 0.1)
				(type default)
			)
			(layer "B.Fab")
		)
		(fp_line
			(start -0.12065 -0.2794)
			(end -0.12065 -0.3048)
			(stroke
				(width 0.1)
				(type default)
			)
			(layer "B.Fab")
		)
		(fp_line
			(start 0.12065 -0.2794)
			(end -0.12065 -0.2794)
			(stroke
				(width 0.1)
				(type default)
			)
			(layer "B.Fab")
		)
		(fp_line
			(start -0.67945 -0.3048)
			(end -0.67945 0.3048)
			(stroke
				(width 0.1)
				(type default)
			)
			(layer "B.Fab")
		)
		(fp_line
			(start -0.12065 -0.3048)
			(end -0.67945 -0.3048)
			(stroke
				(width 0.1)
				(type default)
			)
			(layer "B.Fab")
		)
		(fp_line
			(start 0.12065 -0.305054)
			(end 0.12065 -0.2794)
			(stroke
				(width 0.1)
				(type default)
			)
			(layer "B.Fab")
		)
		(fp_line
			(start 0.67945 -0.305054)
			(end 0.12065 -0.305054)
			(stroke
				(width 0.1)
				(type default)
			)
			(layer "B.Fab")
		)
		(pad "1" smd circle
			(at 0.40005 0 90)
			(size 0 0)
			(layers "B.Cu" "B.Mask" "B.Paste")
			(net "P5V_AUX")
		)
		(pad "2" smd circle
			(at -0.40005 0 90)
			(size 0 0)
			(layers "B.Cu" "B.Mask" "B.Paste")
			(net "PWR_LED_BUF_N_R")
		)
	)
)
